(kicad_pcb
	(version 20260206)
	(generator "pcbnew")
	(generator_version "10.0")
	(general
		(thickness 1.6)
		(legacy_teardrops no)
	)
	(paper "A4")
	(title_block
		(title "12092022_DA0F0TFB6D0_F0T_FAN_BOARD_MP5048_D_brd_v02_OCP.brd")
		(comment 1 "Grand Teton / footprints 872-877 of 924")
	)
	(layers
		(0 "F.Cu" signal "TOP")
		(4 "In1.Cu" signal "GND")
		(6 "In2.Cu" signal "IN1")
		(8 "In3.Cu" signal "IN2")
		(10 "In4.Cu" signal "GND1")
		(2 "B.Cu" signal "BOTTOM")
		(9 "F.Adhes" user "F.Adhesive")
		(11 "B.Adhes" user "B.Adhesive")
		(13 "F.Paste" user "Package Geometry/Pastemask Top")
		(15 "B.Paste" user "Package Geometry/Pastemask Bottom")
		(5 "F.SilkS" user "Ref Des/Silkscreen Top")
		(7 "B.SilkS" user "Ref Des/Silkscreen Bottom")
		(1 "F.Mask" user "Board Geometry/Soldermask Top")
		(3 "B.Mask" user "Board Geometry/Soldermask Bottom")
		(17 "Dwgs.User" user "User.Drawings")
		(19 "Cmts.User" user "User.Comments")
		(21 "Eco1.User" user "User.Eco1")
		(23 "Eco2.User" user "User.Eco2")
		(25 "Edge.Cuts" user "Board Geometry/Outline")
		(27 "Margin" user)
		(31 "F.CrtYd" user "Package Geometry/Place Bound Top")
		(29 "B.CrtYd" user "Package Geometry/Place Bound Bottom")
		(35 "F.Fab" user "Ref Des/Assembly Top")
		(33 "B.Fab" user "Ref Des/Assembly Bottom")
	)
	(footprint ""
		(layer "B.Cu")
		(at 41.12768 -250.23699 -90)
		(property "Reference" "PR32"
			(at 0 0 90)
			(layer "B.SilkS")
			(hide yes)
			(effects
				(font
					(size 1.27 1.27)
				)
				(justify mirror)
			)
		)
		(property "Value" ""
			(at 0 0 90)
			(layer "B.Fab")
			(effects
				(font
					(size 1.27 1.27)
				)
				(justify mirror)
			)
		)
		(duplicate_pad_numbers_are_jumpers no)
		(fp_line
			(start -0.7874 0.4064)
			(end 0.7874 0.4064)
			(stroke
				(width 0.1524)
				(type default)
			)
			(layer "B.SilkS")
		)
		(fp_line
			(start 0.7874 0.4064)
			(end 0.7874 -0.4064)
			(stroke
				(width 0.1524)
				(type default)
			)
			(layer "B.SilkS")
		)
		(fp_line
			(start -0.7874 -0.4064)
			(end -0.7874 0.4064)
			(stroke
				(width 0.1524)
				(type default)
			)
			(layer "B.SilkS")
		)
		(fp_line
			(start 0.7874 -0.4064)
			(end -0.7874 -0.4064)
			(stroke
				(width 0.1524)
				(type default)
			)
			(layer "B.SilkS")
		)
		(fp_line
			(start -0.67945 0.3048)
			(end -0.120396 0.3048)
			(stroke
				(width 0.1)
				(type default)
			)
			(layer "B.Fab")
		)
		(fp_line
			(start -0.120396 0.3048)
			(end -0.120396 0.2794)
			(stroke
				(width 0.1)
				(type default)
			)
			(layer "B.Fab")
		)
		(fp_line
			(start 0.12065 0.3048)
			(end 0.67945 0.3048)
			(stroke
				(width 0.1)
				(type default)
			)
			(layer "B.Fab")
		)
		(fp_line
			(start 0.67945 0.3048)
			(end 0.67945 -0.305054)
			(stroke
				(width 0.1)
				(type default)
			)
			(layer "B.Fab")
		)
		(fp_line
			(start -0.120396 0.2794)
			(end 0.12065 0.2794)
			(stroke
				(width 0.1)
				(type default)
			)
			(layer "B.Fab")
		)
		(fp_line
			(start 0.12065 0.2794)
			(end 0.12065 0.3048)
			(stroke
				(width 0.1)
				(type default)
			)
			(layer "B.Fab")
		)
		(fp_line
			(start -0.12065 -0.2794)
			(end -0.12065 -0.3048)
			(stroke
				(width 0.1)
				(type default)
			)
			(layer "B.Fab")
		)
		(fp_line
			(start 0.12065 -0.2794)
			(end -0.12065 -0.2794)
			(stroke
				(width 0.1)
				(type default)
			)
			(layer "B.Fab")
		)
		(fp_line
			(start -0.67945 -0.3048)
			(end -0.67945 0.3048)
			(stroke
				(width 0.1)
				(type default)
			)
			(layer "B.Fab")
		)
		(fp_line
			(start -0.12065 -0.3048)
			(end -0.67945 -0.3048)
			(stroke
				(width 0.1)
				(type default)
			)
			(layer "B.Fab")
		)
		(fp_line
			(start 0.12065 -0.305054)
			(end 0.12065 -0.2794)
			(stroke
				(width 0.1)
				(type default)
			)
			(layer "B.Fab")
		)
		(fp_line
			(start 0.67945 -0.305054)
			(end 0.12065 -0.305054)
			(stroke
				(width 0.1)
				(type default)
			)
			(layer "B.Fab")
		)
		(pad "1" smd circle
			(at 0.40005 0 90)
			(size 0 0)
			(layers "B.Cu" "B.Mask" "B.Paste")
			(net "FAN_1_TEMP")
		)
		(pad "2" smd circle
			(at -0.40005 0 90)
			(size 0 0)
			(layers "B.Cu" "B.Mask" "B.Paste")
			(net "GND")
		)
	)
	(footprint ""
		(layer "B.Cu")
		(at 16.2052 -88.449912 180)
		(property "Reference" "C2111"
			(at 0 0 0)
			(layer "B.SilkS")
			(hide yes)
			(effects
				(font
					(size 1.27 1.27)
				)
				(justify mirror)
			)
		)
		(property "Value" ""
			(at 0 0 0)
			(layer "B.Fab")
			(effects
				(font
					(size 1.27 1.27)
				)
				(justify mirror)
			)
		)
		(duplicate_pad_numbers_are_jumpers no)
		(fp_line
			(start 2.2098 0.9398)
			(end 2.2098 -0.9398)
			(stroke
				(width 0.1524)
				(type default)
			)
			(layer "B.SilkS")
		)
		(fp_line
			(start 2.2098 -0.9398)
			(end -2.2098 -0.9398)
			(stroke
				(width 0.1524)
				(type default)
			)
			(layer "B.SilkS")
		)
		(fp_line
			(start -2.2098 0.9398)
			(end 2.2098 0.9398)
			(stroke
				(width 0.1524)
				(type default)
			)
			(layer "B.SilkS")
		)
		(fp_line
			(start -2.2098 -0.9398)
			(end -2.2098 0.9398)
			(stroke
				(width 0.1524)
				(type default)
			)
			(layer "B.SilkS")
		)
		(fp_line
			(start 1.700022 0.899922)
			(end 1.700022 -0.899922)
			(stroke
				(width 0.1)
				(type default)
			)
			(layer "B.Fab")
		)
		(fp_line
			(start 1.700022 -0.899922)
			(end -1.700022 -0.899922)
			(stroke
				(width 0.1)
				(type default)
			)
			(layer "B.Fab")
		)
		(fp_line
			(start -1.700022 0.899922)
			(end 1.700022 0.899922)
			(stroke
				(width 0.1)
				(type default)
			)
			(layer "B.Fab")
		)
		(fp_line
			(start -1.700022 -0.899922)
			(end -1.700022 0.899922)
			(stroke
				(width 0.1)
				(type default)
			)
			(layer "B.Fab")
		)
		(pad "1" smd rect
			(at 1.4732 0 180)
			(size 1.1684 1.5748)
			(layers "B.Cu" "B.Mask" "B.Paste")
			(net "P52V_FAN_5")
		)
		(pad "2" smd rect
			(at -1.4732 0 180)
			(size 1.1684 1.5748)
			(layers "B.Cu" "B.Mask" "B.Paste")
			(net "GND")
		)
	)
	(footprint ""
		(layer "B.Cu")
		(at 43.434 -73.971912 90)
		(property "Reference" "PR41"
			(at 0 0 90)
			(layer "B.SilkS")
			(hide yes)
			(effects
				(font
					(size 1.27 1.27)
				)
				(justify mirror)
			)
		)
		(property "Value" ""
			(at 0 0 90)
			(layer "B.Fab")
			(effects
				(font
					(size 1.27 1.27)
				)
				(justify mirror)
			)
		)
		(duplicate_pad_numbers_are_jumpers no)
		(fp_line
			(start 0.7874 -0.4064)
			(end -0.7874 -0.4064)
			(stroke
				(width 0.1524)
				(type default)
			)
			(layer "B.SilkS")
		)
		(fp_line
			(start -0.7874 -0.4064)
			(end -0.7874 0.4064)
			(stroke
				(width 0.1524)
				(type default)
			)
			(layer "B.SilkS")
		)
		(fp_line
			(start 0.7874 0.4064)
			(end 0.7874 -0.4064)
			(stroke
				(width 0.1524)
				(type default)
			)
			(layer "B.SilkS")
		)
		(fp_line
			(start -0.7874 0.4064)
			(end 0.7874 0.4064)
			(stroke
				(width 0.1524)
				(type default)
			)
			(layer "B.SilkS")
		)
		(fp_line
			(start 0.67945 -0.305054)
			(end 0.12065 -0.305054)
			(stroke
				(width 0.1)
				(type default)
			)
			(layer "B.Fab")
		)
		(fp_line
			(start 0.12065 -0.305054)
			(end 0.12065 -0.2794)
			(stroke
				(width 0.1)
				(type default)
			)
			(layer "B.Fab")
		)
		(fp_line
			(start -0.12065 -0.3048)
			(end -0.67945 -0.3048)
			(stroke
				(width 0.1)
				(type default)
			)
			(layer "B.Fab")
		)
		(fp_line
			(start -0.67945 -0.3048)
			(end -0.67945 0.3048)
			(stroke
				(width 0.1)
				(type default)
			)
			(layer "B.Fab")
		)
		(fp_line
			(start 0.12065 -0.2794)
			(end -0.12065 -0.2794)
			(stroke
				(width 0.1)
				(type default)
			)
			(layer "B.Fab")
		)
		(fp_line
			(start -0.12065 -0.2794)
			(end -0.12065 -0.3048)
			(stroke
				(width 0.1)
				(type default)
			)
			(layer "B.Fab")
		)
		(fp_line
			(start 0.12065 0.2794)
			(end 0.12065 0.3048)
			(stroke
				(width 0.1)
				(type default)
			)
			(layer "B.Fab")
		)
		(fp_line
			(start -0.120396 0.2794)
			(end 0.12065 0.2794)
			(stroke
				(width 0.1)
				(type default)
			)
			(layer "B.Fab")
		)
		(fp_line
			(start 0.67945 0.3048)
			(end 0.67945 -0.305054)
			(stroke
				(width 0.1)
				(type default)
			)
			(layer "B.Fab")
		)
		(fp_line
			(start 0.12065 0.3048)
			(end 0.67945 0.3048)
			(stroke
				(width 0.1)
				(type default)
			)
			(layer "B.Fab")
		)
		(fp_line
			(start -0.120396 0.3048)
			(end -0.120396 0.2794)
			(stroke
				(width 0.1)
				(type default)
			)
			(layer "B.Fab")
		)
		(fp_line
			(start -0.67945 0.3048)
			(end -0.120396 0.3048)
			(stroke
				(width 0.1)
				(type default)
			)
			(layer "B.Fab")
		)
		(pad "1" smd circle
			(at 0.40005 0 270)
			(size 0 0)
			(layers "B.Cu" "B.Mask" "B.Paste")
			(net "FAN_2_CLREF")
		)
		(pad "2" smd circle
			(at -0.40005 0 270)
			(size 0 0)
			(layers "B.Cu" "B.Mask" "B.Paste")
			(net "GND")
		)
	)
	(footprint ""
		(layer "B.Cu")
		(at 37.465 -258.572 90)
		(property "Reference" "PC2118"
			(at 0 0 90)
			(layer "B.SilkS")
			(hide yes)
			(effects
				(font
					(size 1.27 1.27)
				)
				(justify mirror)
			)
		)
		(property "Value" ""
			(at 0 0 90)
			(layer "B.Fab")
			(effects
				(font
					(size 1.27 1.27)
				)
				(justify mirror)
			)
		)
		(duplicate_pad_numbers_are_jumpers no)
		(fp_line
			(start 0.7874 -0.4064)
			(end -0.7874 -0.4064)
			(stroke
				(width 0.1524)
				(type default)
			)
			(layer "B.SilkS")
		)
		(fp_line
			(start -0.7874 -0.4064)
			(end -0.7874 0.4064)
			(stroke
				(width 0.1524)
				(type default)
			)
			(layer "B.SilkS")
		)
		(fp_line
			(start 0.7874 0.4064)
			(end 0.7874 -0.4064)
			(stroke
				(width 0.1524)
				(type default)
			)
			(layer "B.SilkS")
		)
		(fp_line
			(start -0.7874 0.4064)
			(end 0.7874 0.4064)
			(stroke
				(width 0.1524)
				(type default)
			)
			(layer "B.SilkS")
		)
		(fp_line
			(start 0.67945 -0.305054)
			(end 0.12065 -0.305054)
			(stroke
				(width 0.1)
				(type default)
			)
			(layer "B.Fab")
		)
		(fp_line
			(start 0.12065 -0.305054)
			(end 0.12065 -0.2794)
			(stroke
				(width 0.1)
				(type default)
			)
			(layer "B.Fab")
		)
		(fp_line
			(start -0.12065 -0.3048)
			(end -0.67945 -0.3048)
			(stroke
				(width 0.1)
				(type default)
			)
			(layer "B.Fab")
		)
		(fp_line
			(start -0.67945 -0.3048)
			(end -0.67945 0.3048)
			(stroke
				(width 0.1)
				(type default)
			)
			(layer "B.Fab")
		)
		(fp_line
			(start 0.12065 -0.2794)
			(end -0.12065 -0.2794)
			(stroke
				(width 0.1)
				(type default)
			)
			(layer "B.Fab")
		)
		(fp_line
			(start -0.12065 -0.2794)
			(end -0.12065 -0.3048)
			(stroke
				(width 0.1)
				(type default)
			)
			(layer "B.Fab")
		)
		(fp_line
			(start 0.12065 0.2794)
			(end 0.12065 0.3048)
			(stroke
				(width 0.1)
				(type default)
			)
			(layer "B.Fab")
		)
		(fp_line
			(start -0.120396 0.2794)
			(end 0.12065 0.2794)
			(stroke
				(width 0.1)
				(type default)
			)
			(layer "B.Fab")
		)
		(fp_line
			(start 0.67945 0.3048)
			(end 0.67945 -0.305054)
			(stroke
				(width 0.1)
				(type default)
			)
			(layer "B.Fab")
		)
		(fp_line
			(start 0.12065 0.3048)
			(end 0.67945 0.3048)
			(stroke
				(width 0.1)
				(type default)
			)
			(layer "B.Fab")
		)
		(fp_line
			(start -0.120396 0.3048)
			(end -0.120396 0.2794)
			(stroke
				(width 0.1)
				(type default)
			)
			(layer "B.Fab")
		)
		(fp_line
			(start -0.67945 0.3048)
			(end -0.120396 0.3048)
			(stroke
				(width 0.1)
				(type default)
			)
			(layer "B.Fab")
		)
		(pad "1" smd circle
			(at 0.40005 0 270)
			(size 0 0)
			(layers "B.Cu" "B.Mask" "B.Paste")
			(net "FAN_0_TEMP")
		)
		(pad "2" smd circle
			(at -0.40005 0 270)
			(size 0 0)
			(layers "B.Cu" "B.Mask" "B.Paste")
			(net "GND")
		)
	)
	(footprint ""
		(layer "B.Cu")
		(at 40.894 -130.048 180)
		(property "Reference" "R5430"
			(at 0 0 0)
			(layer "B.SilkS")
			(hide yes)
			(effects
				(font
					(size 1.27 1.27)
				)
				(justify mirror)
			)
		)
		(property "Value" ""
			(at 0 0 0)
			(layer "B.Fab")
			(effects
				(font
					(size 1.27 1.27)
				)
				(justify mirror)
			)
		)
		(duplicate_pad_numbers_are_jumpers no)
		(fp_line
			(start 0.7874 0.4064)
			(end 0.7874 -0.4064)
			(stroke
				(width 0.1524)
				(type default)
			)
			(layer "B.SilkS")
		)
		(fp_line
			(start 0.7874 -0.4064)
			(end -0.7874 -0.4064)
			(stroke
				(width 0.1524)
				(type default)
			)
			(layer "B.SilkS")
		)
		(fp_line
			(start -0.7874 0.4064)
			(end 0.7874 0.4064)
			(stroke
				(width 0.1524)
				(type default)
			)
			(layer "B.SilkS")
		)
		(fp_line
			(start -0.7874 -0.4064)
			(end -0.7874 0.4064)
			(stroke
				(width 0.1524)
				(type default)
			)
			(layer "B.SilkS")
		)
		(fp_line
			(start 0.67945 0.3048)
			(end 0.67945 -0.305054)
			(stroke
				(width 0.1)
				(type default)
			)
			(layer "B.Fab")
		)
		(fp_line
			(start 0.67945 -0.305054)
			(end 0.12065 -0.305054)
			(stroke
				(width 0.1)
				(type default)
			)
			(layer "B.Fab")
		)
		(fp_line
			(start 0.12065 0.3048)
			(end 0.67945 0.3048)
			(stroke
				(width 0.1)
				(type default)
			)
			(layer "B.Fab")
		)
		(fp_line
			(start 0.12065 0.2794)
			(end 0.12065 0.3048)
			(stroke
				(width 0.1)
				(type default)
			)
			(layer "B.Fab")
		)
		(fp_line
			(start 0.12065 -0.2794)
			(end -0.12065 -0.2794)
			(stroke
				(width 0.1)
				(type default)
			)
			(layer "B.Fab")
		)
		(fp_line
			(start 0.12065 -0.305054)
			(end 0.12065 -0.2794)
			(stroke
				(width 0.1)
				(type default)
			)
			(layer "B.Fab")
		)
		(fp_line
			(start -0.120396 0.3048)
			(end -0.120396 0.2794)
			(stroke
				(width 0.1)
				(type default)
			)
			(layer "B.Fab")
		)
		(fp_line
			(start -0.120396 0.2794)
			(end 0.12065 0.2794)
			(stroke
				(width 0.1)
				(type default)
			)
			(layer "B.Fab")
		)
		(fp_line
			(start -0.12065 -0.2794)
			(end -0.12065 -0.3048)
			(stroke
				(width 0.1)
				(type default)
			)
			(layer "B.Fab")
		)
		(fp_line
			(start -0.12065 -0.3048)
			(end -0.67945 -0.3048)
			(stroke
				(width 0.1)
				(type default)
			)
			(layer "B.Fab")
		)
		(fp_line
			(start -0.67945 0.3048)
			(end -0.120396 0.3048)
			(stroke
				(width 0.1)
				(type default)
			)
			(layer "B.Fab")
		)
		(fp_line
			(start -0.67945 -0.3048)
			(end -0.67945 0.3048)
			(stroke
				(width 0.1)
				(type default)
			)
			(layer "B.Fab")
		)
		(pad "1" smd rect
			(at 0.40005 0 180)
			(size 0.4572 0.508)
			(layers "B.Cu" "B.Mask" "B.Paste")
			(net "FAN_2_TACH_IL")
		)
		(pad "2" smd rect
			(at -0.40005 0 180)
			(size 0.4572 0.508)
			(layers "B.Cu" "B.Mask" "B.Paste")
			(net "GND")
		)
	)
	(footprint ""
		(layer "B.Cu")
		(at 1.651 -249.428 -90)
		(property "Reference" "PR66"
			(at 0 0 90)
			(layer "B.SilkS")
			(hide yes)
			(effects
				(font
					(size 1.27 1.27)
				)
				(justify mirror)
			)
		)
		(property "Value" ""
			(at 0 0 90)
			(layer "B.Fab")
			(effects
				(font
					(size 1.27 1.27)
				)
				(justify mirror)
			)
		)
		(duplicate_pad_numbers_are_jumpers no)
		(fp_line
			(start -0.7874 0.4064)
			(end 0.7874 0.4064)
			(stroke
				(width 0.1524)
				(type default)
			)
			(layer "B.SilkS")
		)
		(fp_line
			(start 0.7874 0.4064)
			(end 0.7874 -0.4064)
			(stroke
				(width 0.1524)
				(type default)
			)
			(layer "B.SilkS")
		)
		(fp_line
			(start -0.7874 -0.4064)
			(end -0.7874 0.4064)
			(stroke
				(width 0.1524)
				(type default)
			)
			(layer "B.SilkS")
		)
		(fp_line
			(start 0.7874 -0.4064)
			(end -0.7874 -0.4064)
			(stroke
				(width 0.1524)
				(type default)
			)
			(layer "B.SilkS")
		)
		(fp_line
			(start -0.67945 0.3048)
			(end -0.120396 0.3048)
			(stroke
				(width 0.1)
				(type default)
			)
			(layer "B.Fab")
		)
		(fp_line
			(start -0.120396 0.3048)
			(end -0.120396 0.2794)
			(stroke
				(width 0.1)
				(type default)
			)
			(layer "B.Fab")
		)
		(fp_line
			(start 0.12065 0.3048)
			(end 0.67945 0.3048)
			(stroke
				(width 0.1)
				(type default)
			)
			(layer "B.Fab")
		)
		(fp_line
			(start 0.67945 0.3048)
			(end 0.67945 -0.305054)
			(stroke
				(width 0.1)
				(type default)
			)
			(layer "B.Fab")
		)
		(fp_line
			(start -0.120396 0.2794)
			(end 0.12065 0.2794)
			(stroke
				(width 0.1)
				(type default)
			)
			(layer "B.Fab")
		)
		(fp_line
			(start 0.12065 0.2794)
			(end 0.12065 0.3048)
			(stroke
				(width 0.1)
				(type default)
			)
			(layer "B.Fab")
		)
		(fp_line
			(start -0.12065 -0.2794)
			(end -0.12065 -0.3048)
			(stroke
				(width 0.1)
				(type default)
			)
			(layer "B.Fab")
		)
		(fp_line
			(start 0.12065 -0.2794)
			(end -0.12065 -0.2794)
			(stroke
				(width 0.1)
				(type default)
			)
			(layer "B.Fab")
		)
		(fp_line
			(start -0.67945 -0.3048)
			(end -0.67945 0.3048)
			(stroke
				(width 0.1)
				(type default)
			)
			(layer "B.Fab")
		)
		(fp_line
			(start -0.12065 -0.3048)
			(end -0.67945 -0.3048)
			(stroke
				(width 0.1)
				(type default)
			)
			(layer "B.Fab")
		)
		(fp_line
			(start 0.12065 -0.305054)
			(end 0.12065 -0.2794)
			(stroke
				(width 0.1)
				(type default)
			)
			(layer "B.Fab")
		)
		(fp_line
			(start 0.67945 -0.305054)
			(end 0.12065 -0.305054)
			(stroke
				(width 0.1)
				(type default)
			)
			(layer "B.Fab")
		)
		(pad "1" smd circle
			(at 0.40005 0 90)
			(size 0 0)
			(layers "B.Cu" "B.Mask" "B.Paste")
			(net "FAN_6_CS")
		)
		(pad "2" smd circle
			(at -0.40005 0 90)
			(size 0 0)
			(layers "B.Cu" "B.Mask" "B.Paste")
			(net "GND")
		)
	)
)
